(kicad_pcb
	(version 20260206)
	(generator "pcbnew")
	(generator_version "10.0")
	(general
		(thickness 1.6)
		(legacy_teardrops no)
	)
	(paper "A4")
	(title_block
		(title "fcb — 12433-1M.1206WZS1330.brd")
		(comment 1 "Open Vault / Knox (Wiwynn) / footprints 341-346 of 495")
	)
	(layers
		(0 "F.Cu" signal "TOP")
		(4 "In1.Cu" signal "L2GND")
		(6 "In2.Cu" signal "L3VCC")
		(2 "B.Cu" signal "BOTTOM")
		(9 "F.Adhes" user "F.Adhesive")
		(11 "B.Adhes" user "B.Adhesive")
		(13 "F.Paste" user "Package Geometry/Pastemask Top")
		(15 "B.Paste" user "Package Geometry/Pastemask Bottom")
		(5 "F.SilkS" user "Ref Des/Silkscreen Top")
		(7 "B.SilkS" user "Ref Des/Silkscreen Bottom")
		(1 "F.Mask" user "Board Geometry/Soldermask Top")
		(3 "B.Mask" user "Board Geometry/Soldermask Bottom")
		(17 "Dwgs.User" user "User.Drawings")
		(19 "Cmts.User" user "User.Comments")
		(21 "Eco1.User" user "User.Eco1")
		(23 "Eco2.User" user "User.Eco2")
		(25 "Edge.Cuts" user "Board Geometry/Outline")
		(27 "Margin" user)
		(31 "F.CrtYd" user "Package Geometry/Place Bound Top")
		(29 "B.CrtYd" user "Package Geometry/Place Bound Bottom")
		(35 "F.Fab" user "Ref Des/Assembly Top")
		(33 "B.Fab" user "Ref Des/Assembly Bottom")
	)
	(footprint ""
		(layer "F.Cu")
		(at 28.2956 -362.1786 90)
		(property "Reference" "PR12"
			(at 0 0 90)
			(layer "F.SilkS")
			(hide yes)
			(effects
				(font
					(size 1.27 1.27)
				)
			)
		)
		(property "Value" "0R2J-2-GP"
			(at 0.064008 -3.993896 90)
			(unlocked yes)
			(layer "F.Fab")
			(hide yes)
			(effects
				(font
					(size 1.016 1.016)
					(thickness 0.1524)
				)
			)
		)
		(property "Device Type" "R402H16"
			(at 0.064008 -5.517896 90)
			(unlocked yes)
			(layer "F.Fab")
			(hide yes)
			(effects
				(font
					(size 1.016 1.016)
					(thickness 0.1524)
				)
			)
		)
		(duplicate_pad_numbers_are_jumpers no)
		(fp_line
			(start 0.508 -0.9398)
			(end -0.508 -0.9398)
			(stroke
				(width 0.1524)
				(type default)
			)
			(layer "F.SilkS")
		)
		(fp_line
			(start -0.508 -0.9398)
			(end -0.508 0.9398)
			(stroke
				(width 0.1524)
				(type default)
			)
			(layer "F.SilkS")
		)
		(fp_rect
			(start -0.508 0.9398)
			(end 0.508 -0.9398)
			(stroke
				(width 0)
				(type default)
			)
			(fill no)
			(layer "F.CrtYd")
		)
		(fp_rect
			(start -0.508 0.9398)
			(end 0.508 -0.9398)
			(stroke
				(width 0)
				(type default)
			)
			(fill no)
			(layer "F.Fab")
		)
		(pad "1" smd custom
			(at 0 -0.4445 90)
			(size 0.1397 0.1397)
			(layers "F.Cu" "F.Mask" "F.Paste")
			(net "ADM1276_LATCH#")
			(options
				(clearance outline)
				(anchor circle)
			)
			(primitives
				(gr_poly
					(pts
						(arc
							(start -0.1778 -0.2794)
							(mid -0.249642 -0.249642)
							(end -0.2794 -0.1778)
						)
						(arc
							(start -0.2794 0.1778)
							(mid -0.249642 0.249642)
							(end -0.1778 0.2794)
						)
						(arc
							(start 0.1778 0.2794)
							(mid 0.249642 0.249642)
							(end 0.2794 0.1778)
						)
						(arc
							(start 0.2794 -0.1778)
							(mid 0.249642 -0.249642)
							(end 0.1778 -0.2794)
						)
					)
					(width 0)
					(fill yes)
				)
			)
		)
		(pad "2" smd custom
			(at 0 0.4445 90)
			(size 0.1397 0.1397)
			(layers "F.Cu" "F.Mask" "F.Paste")
			(net "ADM1276_EN")
			(options
				(clearance outline)
				(anchor circle)
			)
			(primitives
				(gr_poly
					(pts
						(arc
							(start -0.1778 -0.2794)
							(mid -0.249642 -0.249642)
							(end -0.2794 -0.1778)
						)
						(arc
							(start -0.2794 0.1778)
							(mid -0.249642 0.249642)
							(end -0.1778 0.2794)
						)
						(arc
							(start 0.1778 0.2794)
							(mid 0.249642 0.249642)
							(end 0.2794 0.1778)
						)
						(arc
							(start 0.2794 -0.1778)
							(mid 0.249642 -0.249642)
							(end 0.1778 -0.2794)
						)
					)
					(width 0)
					(fill yes)
				)
			)
		)
	)
	(footprint ""
		(layer "F.Cu")
		(at 16.2052 -249.1994 180)
		(property "Reference" "PC40"
			(at 0 0 180)
			(layer "F.SilkS")
			(hide yes)
			(effects
				(font
					(size 1.27 1.27)
				)
			)
		)
		(property "Value" "SC4D7U50V6KX-L2-GP"
			(at 0 -6.8072 180)
			(unlocked yes)
			(layer "F.Fab")
			(hide yes)
			(effects
				(font
					(size 1.016 1.016)
					(thickness 0.1524)
				)
			)
		)
		(property "Device Type" "C1206H38"
			(at 0 -8.7122 180)
			(unlocked yes)
			(layer "F.Fab")
			(hide yes)
			(effects
				(font
					(size 1.016 1.016)
					(thickness 0.1524)
				)
			)
		)
		(duplicate_pad_numbers_are_jumpers no)
		(fp_line
			(start 1.016 2.2352)
			(end -1.016 2.2352)
			(stroke
				(width 0.1524)
				(type default)
			)
			(layer "F.SilkS")
		)
		(fp_line
			(start 1.016 0.8382)
			(end 1.016 2.2352)
			(stroke
				(width 0.1524)
				(type default)
			)
			(layer "F.SilkS")
		)
		(fp_line
			(start 1.016 -2.2352)
			(end 1.016 -0.8382)
			(stroke
				(width 0.1524)
				(type default)
			)
			(layer "F.SilkS")
		)
		(fp_line
			(start 1.016 -2.2352)
			(end -1.016 -2.2352)
			(stroke
				(width 0.1524)
				(type default)
			)
			(layer "F.SilkS")
		)
		(fp_line
			(start -1.016 2.2352)
			(end -1.016 0.8128)
			(stroke
				(width 0.1524)
				(type default)
			)
			(layer "F.SilkS")
		)
		(fp_line
			(start -1.016 -2.2352)
			(end -1.016 -0.8382)
			(stroke
				(width 0.1524)
				(type default)
			)
			(layer "F.SilkS")
		)
		(fp_rect
			(start -1.0922 2.3114)
			(end 1.0922 -2.3114)
			(stroke
				(width 0)
				(type default)
			)
			(fill no)
			(layer "F.CrtYd")
		)
		(fp_poly
			(pts
				(xy -1.0922 -2.3114) (xy 1.0922 -2.3114) (xy 1.0922 2.3114) (xy -1.0922 2.3114)
			)
			(stroke
				(width 0)
				(type default)
			)
			(fill no)
			(layer "F.Fab")
		)
		(pad "1" smd rect
			(at 0 -1.397 180)
			(size 1.651 1.27)
			(layers "F.Cu" "F.Mask" "F.Paste")
			(net "P3V3_IN")
		)
		(pad "2" smd rect
			(at 0 1.397 180)
			(size 1.651 1.27)
			(layers "F.Cu" "F.Mask" "F.Paste")
			(net "GND")
		)
	)
	(footprint ""
		(layer "F.Cu")
		(at 15.5956 -171.4754)
		(property "Reference" "R52"
			(at 0 0 0)
			(layer "F.SilkS")
			(hide yes)
			(effects
				(font
					(size 1.27 1.27)
				)
			)
		)
		(property "Value" "4K7R2F-GP"
			(at 0.064008 -3.993896 0)
			(unlocked yes)
			(layer "F.Fab")
			(hide yes)
			(effects
				(font
					(size 1.016 1.016)
					(thickness 0.1524)
				)
			)
		)
		(property "Device Type" "R402H16"
			(at 0.064008 -5.517896 0)
			(unlocked yes)
			(layer "F.Fab")
			(hide yes)
			(effects
				(font
					(size 1.016 1.016)
					(thickness 0.1524)
				)
			)
		)
		(duplicate_pad_numbers_are_jumpers no)
		(fp_line
			(start -0.508 -0.9398)
			(end -0.508 0.9398)
			(stroke
				(width 0.1524)
				(type default)
			)
			(layer "F.SilkS")
		)
		(fp_line
			(start 0.508 -0.9398)
			(end -0.508 -0.9398)
			(stroke
				(width 0.1524)
				(type default)
			)
			(layer "F.SilkS")
		)
		(fp_rect
			(start -0.508 0.9398)
			(end 0.508 -0.9398)
			(stroke
				(width 0)
				(type default)
			)
			(fill no)
			(layer "F.CrtYd")
		)
		(fp_rect
			(start -0.508 0.9398)
			(end 0.508 -0.9398)
			(stroke
				(width 0)
				(type default)
			)
			(fill no)
			(layer "F.Fab")
		)
		(pad "1" smd custom
			(at 0 -0.4445)
			(size 0.1397 0.1397)
			(layers "F.Cu" "F.Mask" "F.Paste")
			(net "P3V3")
			(options
				(clearance outline)
				(anchor circle)
			)
			(primitives
				(gr_poly
					(pts
						(arc
							(start -0.1778 -0.2794)
							(mid -0.249642 -0.249642)
							(end -0.2794 -0.1778)
						)
						(arc
							(start -0.2794 0.1778)
							(mid -0.249642 0.249642)
							(end -0.1778 0.2794)
						)
						(arc
							(start 0.1778 0.2794)
							(mid 0.249642 0.249642)
							(end 0.2794 0.1778)
						)
						(arc
							(start 0.2794 -0.1778)
							(mid 0.249642 -0.249642)
							(end 0.1778 -0.2794)
						)
					)
					(width 0)
					(fill yes)
				)
			)
		)
		(pad "2" smd custom
			(at 0 0.4445)
			(size 0.1397 0.1397)
			(layers "F.Cu" "F.Mask" "F.Paste")
			(net "SEB_PEER_2A_2B_HB_OUT")
			(options
				(clearance outline)
				(anchor circle)
			)
			(primitives
				(gr_poly
					(pts
						(arc
							(start -0.1778 -0.2794)
							(mid -0.249642 -0.249642)
							(end -0.2794 -0.1778)
						)
						(arc
							(start -0.2794 0.1778)
							(mid -0.249642 0.249642)
							(end -0.1778 0.2794)
						)
						(arc
							(start 0.1778 0.2794)
							(mid 0.249642 0.249642)
							(end 0.2794 0.1778)
						)
						(arc
							(start 0.2794 -0.1778)
							(mid 0.249642 -0.249642)
							(end 0.1778 -0.2794)
						)
					)
					(width 0)
					(fill yes)
				)
			)
		)
	)
	(footprint ""
		(layer "F.Cu")
		(at 24.500078 -450.44995 90)
		(property "Reference" "PAD1"
			(at 0 0 90)
			(layer "F.SilkS")
			(hide yes)
			(effects
				(font
					(size 1.27 1.27)
				)
			)
		)
		(property "Value" "PAD-1P-424137-2-OG-GP"
			(at -22.9743 -0.4572 90)
			(unlocked yes)
			(layer "F.Fab")
			(hide yes)
			(effects
				(font
					(size 1.016 1.016)
					(thickness 0.1524)
				)
			)
		)
		(property "Device Type" "PAD-1P-424137-2-OG"
			(at -22.9743 -1.9812 90)
			(unlocked yes)
			(layer "F.Fab")
			(hide yes)
			(effects
				(font
					(size 1.016 1.016)
					(thickness 0.1524)
				)
			)
		)
		(duplicate_pad_numbers_are_jumpers no)
		(fp_line
			(start 21.4503 -7.0993)
			(end 21.4503 7.0993)
			(stroke
				(width 0.1524)
				(type default)
			)
			(layer "F.SilkS")
		)
		(fp_line
			(start -21.4503 -7.0993)
			(end 21.4503 -7.0993)
			(stroke
				(width 0.1524)
				(type default)
			)
			(layer "F.SilkS")
		)
		(fp_line
			(start -0.075946 5.750052)
			(end -0.075946 7.0993)
			(stroke
				(width 0.1524)
				(type default)
			)
			(layer "F.SilkS")
		)
		(fp_line
			(start 21.4503 7.0993)
			(end 2.816098 7.0993)
			(stroke
				(width 0.1524)
				(type default)
			)
			(layer "F.SilkS")
		)
		(fp_line
			(start 2.816098 7.0993)
			(end 2.816098 5.750052)
			(stroke
				(width 0.1524)
				(type default)
			)
			(layer "F.SilkS")
		)
		(fp_line
			(start -0.075946 7.0993)
			(end -21.4503 7.0993)
			(stroke
				(width 0.1524)
				(type default)
			)
			(layer "F.SilkS")
		)
		(fp_line
			(start -21.4503 7.0993)
			(end -21.4503 -7.0993)
			(stroke
				(width 0.1524)
				(type default)
			)
			(layer "F.SilkS")
		)
		(fp_arc
			(start -0.075946 5.750052)
			(mid 1.37008 4.304026)
			(end 2.816098 5.750052)
			(stroke
				(width 0.1524)
				(type default)
			)
			(layer "F.SilkS")
		)
		(fp_poly
			(pts
				(xy -21.7043 7.3533) (xy -21.7043 -7.3533) (xy 21.7043 -7.3533) (xy 21.7043 7.3533) (xy 2.562098 7.3533)
				(arc
					(start 2.562098 5.750052)
					(mid 1.370076 4.55803)
					(end 0.178054 5.750052)
				)
				(xy 0.178054 7.3533)
			)
			(stroke
				(width 0)
				(type default)
			)
			(fill no)
			(layer "F.CrtYd")
		)
		(fp_poly
			(pts
				(xy -21.7043 7.3533) (xy -21.7043 -7.3533) (xy 21.7043 -7.3533) (xy 21.7043 7.3533) (xy 2.562098 7.3533)
				(arc
					(start 2.562098 5.750052)
					(mid 1.370076 4.55803)
					(end 0.178054 5.750052)
				)
				(xy 0.178054 7.3533)
			)
			(stroke
				(width 0)
				(type default)
			)
			(fill no)
			(layer "F.Fab")
		)
		(pad "1" smd custom
			(at 0 0 90)
			(size 3.425063 3.425063)
			(layers "F.Cu" "F.Mask" "F.Paste")
			(net "P12V_AUX")
			(options
				(clearance outline)
				(anchor circle)
			)
			(primitives
				(gr_poly
					(pts
						(xy -0.329946 6.850126) (xy -21.20011 6.850126) (xy -21.20011 -6.850126) (xy 21.20011 -6.850126)
						(xy 21.20011 6.850126) (xy 3.070098 6.850126)
						(arc
							(start 3.070098 5.750052)
							(mid 1.370076 4.05003)
							(end -0.329946 5.750052)
						)
					)
					(width 0)
					(fill yes)
				)
			)
		)
	)
	(footprint ""
		(layer "F.Cu")
		(at 36.1188 -370.4336 90)
		(property "Reference" "PR8"
			(at 0 0 90)
			(layer "F.SilkS")
			(hide yes)
			(effects
				(font
					(size 1.27 1.27)
				)
			)
		)
		(property "Value" "11KR2F-L-GP"
			(at 0.064008 -3.993896 90)
			(unlocked yes)
			(layer "F.Fab")
			(hide yes)
			(effects
				(font
					(size 1.016 1.016)
					(thickness 0.1524)
				)
			)
		)
		(property "Device Type" "R402H16"
			(at 0.064008 -5.517896 90)
			(unlocked yes)
			(layer "F.Fab")
			(hide yes)
			(effects
				(font
					(size 1.016 1.016)
					(thickness 0.1524)
				)
			)
		)
		(duplicate_pad_numbers_are_jumpers no)
		(fp_line
			(start 0.508 -0.9398)
			(end -0.508 -0.9398)
			(stroke
				(width 0.1524)
				(type default)
			)
			(layer "F.SilkS")
		)
		(fp_line
			(start -0.508 -0.9398)
			(end -0.508 0.9398)
			(stroke
				(width 0.1524)
				(type default)
			)
			(layer "F.SilkS")
		)
		(fp_rect
			(start -0.508 0.9398)
			(end 0.508 -0.9398)
			(stroke
				(width 0)
				(type default)
			)
			(fill no)
			(layer "F.CrtYd")
		)
		(fp_rect
			(start -0.508 0.9398)
			(end 0.508 -0.9398)
			(stroke
				(width 0)
				(type default)
			)
			(fill no)
			(layer "F.Fab")
		)
		(pad "1" smd custom
			(at 0 -0.4445 90)
			(size 0.1397 0.1397)
			(layers "F.Cu" "F.Mask" "F.Paste")
			(net "ADM1276_FLB")
			(options
				(clearance outline)
				(anchor circle)
			)
			(primitives
				(gr_poly
					(pts
						(arc
							(start -0.1778 -0.2794)
							(mid -0.249642 -0.249642)
							(end -0.2794 -0.1778)
						)
						(arc
							(start -0.2794 0.1778)
							(mid -0.249642 0.249642)
							(end -0.1778 0.2794)
						)
						(arc
							(start 0.1778 0.2794)
							(mid 0.249642 0.249642)
							(end 0.2794 0.1778)
						)
						(arc
							(start 0.2794 -0.1778)
							(mid 0.249642 -0.249642)
							(end 0.1778 -0.2794)
						)
					)
					(width 0)
					(fill yes)
				)
			)
		)
		(pad "2" smd custom
			(at 0 0.4445 90)
			(size 0.1397 0.1397)
			(layers "F.Cu" "F.Mask" "F.Paste")
			(net "GND")
			(options
				(clearance outline)
				(anchor circle)
			)
			(primitives
				(gr_poly
					(pts
						(arc
							(start -0.1778 -0.2794)
							(mid -0.249642 -0.249642)
							(end -0.2794 -0.1778)
						)
						(arc
							(start -0.2794 0.1778)
							(mid -0.249642 0.249642)
							(end -0.1778 0.2794)
						)
						(arc
							(start 0.1778 0.2794)
							(mid 0.249642 0.249642)
							(end 0.2794 0.1778)
						)
						(arc
							(start 0.2794 -0.1778)
							(mid 0.249642 -0.249642)
							(end 0.1778 -0.2794)
						)
					)
					(width 0)
					(fill yes)
				)
			)
		)
	)
	(footprint ""
		(layer "F.Cu")
		(at 38.024816 -354.076 -90)
		(property "Reference" "R363"
			(at 0 0 270)
			(layer "F.SilkS")
			(hide yes)
			(effects
				(font
					(size 1.27 1.27)
				)
			)
		)
		(property "Value" "5K1R2F-2-GP"
			(at 0.064008 -3.993896 270)
			(unlocked yes)
			(layer "F.Fab")
			(hide yes)
			(effects
				(font
					(size 1.016 1.016)
					(thickness 0.1524)
				)
			)
		)
		(property "Device Type" "R402H16"
			(at 0.064008 -5.517896 270)
			(unlocked yes)
			(layer "F.Fab")
			(hide yes)
			(effects
				(font
					(size 1.016 1.016)
					(thickness 0.1524)
				)
			)
		)
		(duplicate_pad_numbers_are_jumpers no)
		(fp_line
			(start -0.508 -0.9398)
			(end -0.508 0.9398)
			(stroke
				(width 0.1524)
				(type default)
			)
			(layer "F.SilkS")
		)
		(fp_line
			(start 0.508 -0.9398)
			(end -0.508 -0.9398)
			(stroke
				(width 0.1524)
				(type default)
			)
			(layer "F.SilkS")
		)
		(fp_rect
			(start -0.508 0.9398)
			(end 0.508 -0.9398)
			(stroke
				(width 0)
				(type default)
			)
			(fill no)
			(layer "F.CrtYd")
		)
		(fp_rect
			(start -0.508 0.9398)
			(end 0.508 -0.9398)
			(stroke
				(width 0)
				(type default)
			)
			(fill no)
			(layer "F.Fab")
		)
		(pad "1" smd custom
			(at 0 -0.4445 270)
			(size 0.1397 0.1397)
			(layers "F.Cu" "F.Mask" "F.Paste")
			(net "OTP_RETRY_B")
			(options
				(clearance outline)
				(anchor circle)
			)
			(primitives
				(gr_poly
					(pts
						(arc
							(start -0.1778 -0.2794)
							(mid -0.249642 -0.249642)
							(end -0.2794 -0.1778)
						)
						(arc
							(start -0.2794 0.1778)
							(mid -0.249642 0.249642)
							(end -0.1778 0.2794)
						)
						(arc
							(start 0.1778 0.2794)
							(mid 0.249642 0.249642)
							(end 0.2794 0.1778)
						)
						(arc
							(start 0.2794 -0.1778)
							(mid 0.249642 -0.249642)
							(end 0.1778 -0.2794)
						)
					)
					(width 0)
					(fill yes)
				)
			)
		)
		(pad "2" smd custom
			(at 0 0.4445 270)
			(size 0.1397 0.1397)
			(layers "F.Cu" "F.Mask" "F.Paste")
			(net "GND")
			(options
				(clearance outline)
				(anchor circle)
			)
			(primitives
				(gr_poly
					(pts
						(arc
							(start -0.1778 -0.2794)
							(mid -0.249642 -0.249642)
							(end -0.2794 -0.1778)
						)
						(arc
							(start -0.2794 0.1778)
							(mid -0.249642 0.249642)
							(end -0.1778 0.2794)
						)
						(arc
							(start 0.1778 0.2794)
							(mid 0.249642 0.249642)
							(end 0.2794 0.1778)
						)
						(arc
							(start 0.2794 -0.1778)
							(mid 0.249642 -0.249642)
							(end 0.1778 -0.2794)
						)
					)
					(width 0)
					(fill yes)
				)
			)
		)
	)
)
